FILE_TYPE = CONNECTIVITY;
{Allegro Design Entry HDL 16.6-p007 (v16-6-112F) 10/10/2012}
"PAGE_NUMBER" = 7;
0"NC";
END.
